# T6G (Grand Teton) — schematic netlist excerpt (pin names and nets, part order shuffled) for the footprints in the layout excerpt that follows; sources: Cadence DE-HDL packaged netlist, KiCad conversion of 04192023_DAF0TMB3IC0_F0TG_MB_C_brd_V02_OCP.brd

R9031  Q_RES  33.2 1% CHIP  pkg 0402LF  page 136 : A = OCP_SFF_AUX_PWR_EN_R3 ; B = OCP_SFF_AUX_PWR_EN

(kicad_pcb
	(version 20260206)
	(generator "pcbnew")
	(generator_version "10.0")
	(general
		(thickness 1.6)
		(legacy_teardrops no)
	)
	(paper "A4")
	(title_block
		(title "04192023_DAF0TMB3IC0_F0TG_MB_C_brd_V02_OCP.brd")
		(comment 1 "Grand Teton / footprints 2256-2256 of 8354")
	)
	(layers
		(0 "F.Cu" signal "TOP")
		(4 "In1.Cu" signal "GND")
		(6 "In2.Cu" signal "IN1")
		(8 "In3.Cu" signal "GND1")
		(10 "In4.Cu" signal "IN2")
		(12 "In5.Cu" signal "GND2")
		(14 "In6.Cu" signal "IN3")
		(16 "In7.Cu" signal "GND3")
		(18 "In8.Cu" signal "VCC")
		(20 "In9.Cu" signal "VCC1")
		(22 "In10.Cu" signal "GND4")
		(24 "In11.Cu" signal "IN4")
		(26 "In12.Cu" signal "GND5")
		(28 "In13.Cu" signal "IN5")
		(30 "In14.Cu" signal "GND6")
		(32 "In15.Cu" signal "IN6")
		(34 "In16.Cu" signal "GND7")
		(2 "B.Cu" signal "BOTTOM")
		(9 "F.Adhes" user "F.Adhesive")
		(11 "B.Adhes" user "B.Adhesive")
		(13 "F.Paste" user "Package Geometry/Pastemask Top")
		(15 "B.Paste" user "Package Geometry/Pastemask Bottom")
		(5 "F.SilkS" user "Ref Des/Silkscreen Top")
		(7 "B.SilkS" user "Ref Des/Silkscreen Bottom")
		(1 "F.Mask" user "Board Geometry/Soldermask Top")
		(3 "B.Mask" user "Board Geometry/Soldermask Bottom")
		(17 "Dwgs.User" user "User.Drawings")
		(19 "Cmts.User" user "User.Comments")
		(21 "Eco1.User" user "User.Eco1")
		(23 "Eco2.User" user "User.Eco2")
		(25 "Edge.Cuts" user "Board Geometry/Outline")
		(27 "Margin" user)
		(31 "F.CrtYd" user "Package Geometry/Place Bound Top")
		(29 "B.CrtYd" user "Package Geometry/Place Bound Bottom")
		(35 "F.Fab" user "Ref Des/Assembly Top")
		(33 "B.Fab" user "Ref Des/Assembly Bottom")
	)
	(footprint ""
		(layer "F.Cu")
		(at 215.9 -97.79 180)
		(property "Reference" "R9031"
			(at 0 0 180)
			(layer "F.SilkS")
			(hide yes)
			(effects
				(font
					(size 1.27 1.27)
				)
			)
		)
		(property "Value" ""
			(at 0 0 180)
			(layer "F.Fab")
			(effects
				(font
					(size 1.27 1.27)
				)
			)
		)
		(duplicate_pad_numbers_are_jumpers no)
		(fp_line
			(start 0.7874 0.4064)
			(end -0.7874 0.4064)
			(stroke
				(width 0.1524)
				(type default)
			)
			(layer "F.SilkS")
		)
		(fp_line
			(start 0.7874 -0.4064)
			(end 0.7874 0.4064)
			(stroke
				(width 0.1524)
				(type default)
			)
			(layer "F.SilkS")
		)
		(fp_line
			(start -0.7874 0.4064)
			(end -0.7874 -0.4064)
			(stroke
				(width 0.1524)
				(type default)
			)
			(layer "F.SilkS")
		)
		(fp_line
			(start -0.7874 -0.4064)
			(end 0.7874 -0.4064)
			(stroke
				(width 0.1524)
				(type default)
			)
			(layer "F.SilkS")
		)
		(fp_line
			(start 0.67945 0.3048)
			(end 0.120396 0.3048)
			(stroke
				(width 0.1)
				(type default)
			)
			(layer "F.Fab")
		)
		(fp_line
			(start 0.67945 -0.3048)
			(end 0.67945 0.3048)
			(stroke
				(width 0.1)
				(type default)
			)
			(layer "F.Fab")
		)
		(fp_line
			(start 0.12065 -0.2794)
			(end 0.12065 -0.3048)
			(stroke
				(width 0.1)
				(type default)
			)
			(layer "F.Fab")
		)
		(fp_line
			(start 0.12065 -0.3048)
			(end 0.67945 -0.3048)
			(stroke
				(width 0.1)
				(type default)
			)
			(layer "F.Fab")
		)
		(fp_line
			(start 0.120396 0.3048)
			(end 0.120396 0.2794)
			(stroke
				(width 0.1)
				(type default)
			)
			(layer "F.Fab")
		)
		(fp_line
			(start 0.120396 0.2794)
			(end -0.12065 0.2794)
			(stroke
				(width 0.1)
				(type default)
			)
			(layer "F.Fab")
		)
		(fp_line
			(start -0.12065 0.3048)
			(end -0.67945 0.3048)
			(stroke
				(width 0.1)
				(type default)
			)
			(layer "F.Fab")
		)
		(fp_line
			(start -0.12065 0.2794)
			(end -0.12065 0.3048)
			(stroke
				(width 0.1)
				(type default)
			)
			(layer "F.Fab")
		)
		(fp_line
			(start -0.12065 -0.2794)
			(end 0.12065 -0.2794)
			(stroke
				(width 0.1)
				(type default)
			)
			(layer "F.Fab")
		)
		(fp_line
			(start -0.12065 -0.305054)
			(end -0.12065 -0.2794)
			(stroke
				(width 0.1)
				(type default)
			)
			(layer "F.Fab")
		)
		(fp_line
			(start -0.67945 0.3048)
			(end -0.67945 -0.305054)
			(stroke
				(width 0.1)
				(type default)
			)
			(layer "F.Fab")
		)
		(fp_line
			(start -0.67945 -0.305054)
			(end -0.12065 -0.305054)
			(stroke
				(width 0.1)
				(type default)
			)
			(layer "F.Fab")
		)
		(pad "1" smd circle
			(at -0.40005 0 180)
			(size 0 0)
			(layers "F.Cu" "F.Mask" "F.Paste")
			(net "OCP_SFF_AUX_PWR_EN_R3")
		)
		(pad "2" smd circle
			(at 0.40005 0 180)
			(size 0 0)
			(layers "F.Cu" "F.Mask" "F.Paste")
			(net "OCP_SFF_AUX_PWR_EN")
		)
	)
)
